(kicad_pcb
	(version 20241229)
	(generator "pcbnew")
	(generator_version "9.0")
	(general
		(thickness 1.61)
		(legacy_teardrops no)
	)
	(paper "A3")
	(title_block
		(title "SO-DIMM DDR5 Tester")
		(date "2025-11-26")
		(rev "1.3.0")
		(comment 9 "footprints 350-355 of 627")
	)
	(layers
		(0 "F.Cu" signal)
		(4 "In1.Cu" power)
		(6 "In2.Cu" mixed)
		(8 "In3.Cu" power)
		(10 "In4.Cu" mixed)
		(12 "In5.Cu" power)
		(14 "In6.Cu" mixed)
		(16 "In7.Cu" power)
		(18 "In8.Cu" power)
		(20 "In9.Cu" mixed)
		(22 "In10.Cu" power)
		(2 "B.Cu" signal)
		(9 "F.Adhes" user "F.Adhesive")
		(11 "B.Adhes" user "B.Adhesive")
		(13 "F.Paste" user)
		(15 "B.Paste" user)
		(5 "F.SilkS" user "F.Silkscreen")
		(7 "B.SilkS" user "B.Silkscreen")
		(1 "F.Mask" user)
		(3 "B.Mask" user)
		(17 "Dwgs.User" user "User.Drawings")
		(19 "Cmts.User" user "User.Comments")
		(21 "Eco1.User" user "User.Eco1")
		(23 "Eco2.User" user "User.Eco2")
		(25 "Edge.Cuts" user)
		(27 "Margin" user)
		(31 "F.CrtYd" user "F.Courtyard")
		(29 "B.CrtYd" user "B.Courtyard")
		(35 "F.Fab" user)
		(33 "B.Fab" user)
	)
	(footprint "antmicro-footprints:C_0402_1005Metric"
		(layer "B.Cu")
		(at 90.086829 149.633157 90)
		(descr "Capacitor SMD 0402")
		(tags "capacitor SMD 0402")
		(property "Reference" "C155"
			(at 0 0.699 270)
			(layer "B.SilkS")
			(hide yes)
			(effects
				(font
					(size 0.7 0.7)
					(thickness 0.15)
				)
				(justify left bottom mirror)
			)
		)
		(property "Value" "C_4u7_0402"
			(at -1.022927 -2.155213 270)
			(layer "B.Fab")
			(effects
				(font
					(size 0.7 0.7)
					(thickness 0.15)
				)
				(justify left bottom mirror)
			)
		)
		(property "Datasheet" "https://www.murata.com/products/productdetail?partno=GRM155R61A475MEAA%23"
			(at 0 0 90)
			(layer "F.Fab")
			(hide yes)
			(effects
				(font
					(size 1.27 1.27)
					(thickness 0.15)
				)
			)
		)
		(property "Author" "Antmicro"
			(at 239.719986 59.546328 0)
			(layer "B.Fab")
			(hide yes)
			(effects
				(font
					(size 1 1)
					(thickness 0.15)
				)
				(justify mirror)
			)
		)
		(property "Dielectric" ""
			(at 239.719986 59.546328 0)
			(layer "B.Fab")
			(hide yes)
			(effects
				(font
					(size 1 1)
					(thickness 0.15)
				)
				(justify mirror)
			)
		)
		(property "License" "Apache-2.0"
			(at 239.719986 59.546328 0)
			(layer "B.Fab")
			(hide yes)
			(effects
				(font
					(size 1 1)
					(thickness 0.15)
				)
				(justify mirror)
			)
		)
		(property "MPN" "GRM155R61A475MEAAD"
			(at 239.719986 59.546328 0)
			(layer "B.Fab")
			(hide yes)
			(effects
				(font
					(size 1 1)
					(thickness 0.15)
				)
				(justify mirror)
			)
		)
		(property "Manufacturer" "Murata"
			(at 239.719986 59.546328 0)
			(layer "B.Fab")
			(hide yes)
			(effects
				(font
					(size 1 1)
					(thickness 0.15)
				)
				(justify mirror)
			)
		)
		(property "Val" "4u7"
			(at 239.719986 59.546328 0)
			(layer "B.Fab")
			(hide yes)
			(effects
				(font
					(size 1 1)
					(thickness 0.15)
				)
				(justify mirror)
			)
		)
		(property "Voltage" ""
			(at 239.719986 59.546328 0)
			(layer "B.Fab")
			(hide yes)
			(effects
				(font
					(size 1 1)
					(thickness 0.15)
				)
				(justify mirror)
			)
		)
		(sheetname "/Ethernet/")
		(sheetfile "ethernet.kicad_sch")
		(attr smd)
		(fp_rect
			(start -0.9659 0.481258)
			(end 0.9649 -0.458742)
			(stroke
				(width 0.05)
				(type solid)
			)
			(fill no)
			(layer "B.CrtYd")
		)
		(fp_line
			(start 0.499 -0.248)
			(end -0.499 -0.248)
			(stroke
				(width 0.15)
				(type solid)
			)
			(layer "B.Fab")
		)
		(fp_line
			(start -0.499 -0.248)
			(end -0.499 0.25)
			(stroke
				(width 0.15)
				(type solid)
			)
			(layer "B.Fab")
		)
		(fp_line
			(start 0.499 0.25)
			(end 0.499 -0.248)
			(stroke
				(width 0.15)
				(type solid)
			)
			(layer "B.Fab")
		)
		(fp_line
			(start -0.499 0.25)
			(end 0.499 0.25)
			(stroke
				(width 0.15)
				(type solid)
			)
			(layer "B.Fab")
		)
		(pad "1" smd roundrect
			(at -0.484 0 90)
			(size 0.59 0.64)
			(layers "B.Cu" "B.Mask" "B.Paste")
			(roundrect_rratio 0.25)
			(net 134 "/Ethernet/AVDDH")
			(pintype "passive")
		)
		(pad "2" smd roundrect
			(at 0.484 0 90)
			(size 0.59 0.64)
			(layers "B.Cu" "B.Mask" "B.Paste")
			(roundrect_rratio 0.25)
			(net 1 "GND")
			(pintype "passive")
		)
	)
	(footprint "antmicro-footprints:C_0402_1005Metric"
		(layer "B.Cu")
		(at 92.308672 158.004992 90)
		(descr "Capacitor SMD 0402")
		(tags "capacitor SMD 0402")
		(property "Reference" "C151"
			(at 0 0.699 270)
			(layer "B.SilkS")
			(hide yes)
			(effects
				(font
					(size 0.7 0.7)
					(thickness 0.15)
				)
				(justify left bottom mirror)
			)
		)
		(property "Value" "C_10n_0402"
			(at -1.022927 -2.155213 270)
			(layer "B.Fab")
			(effects
				(font
					(size 0.7 0.7)
					(thickness 0.15)
				)
				(justify left bottom mirror)
			)
		)
		(property "Datasheet" "https://www.murata.com/products/productdetail?partno=GRM155R71H103KA88%23"
			(at 0 0 90)
			(layer "F.Fab")
			(hide yes)
			(effects
				(font
					(size 1.27 1.27)
					(thickness 0.15)
				)
			)
		)
		(property "Author" "Antmicro"
			(at 250.313664 65.69632 0)
			(layer "B.Fab")
			(hide yes)
			(effects
				(font
					(size 1 1)
					(thickness 0.15)
				)
				(justify mirror)
			)
		)
		(property "Dielectric" "X7R"
			(at 250.313664 65.69632 0)
			(layer "B.Fab")
			(hide yes)
			(effects
				(font
					(size 1 1)
					(thickness 0.15)
				)
				(justify mirror)
			)
		)
		(property "License" "Apache-2.0"
			(at 250.313664 65.69632 0)
			(layer "B.Fab")
			(hide yes)
			(effects
				(font
					(size 1 1)
					(thickness 0.15)
				)
				(justify mirror)
			)
		)
		(property "MPN" "GRM155R71H103KA88D"
			(at 250.313664 65.69632 0)
			(layer "B.Fab")
			(hide yes)
			(effects
				(font
					(size 1 1)
					(thickness 0.15)
				)
				(justify mirror)
			)
		)
		(property "Manufacturer" "Murata"
			(at 250.313664 65.69632 0)
			(layer "B.Fab")
			(hide yes)
			(effects
				(font
					(size 1 1)
					(thickness 0.15)
				)
				(justify mirror)
			)
		)
		(property "Val" "10n"
			(at 250.313664 65.69632 0)
			(layer "B.Fab")
			(hide yes)
			(effects
				(font
					(size 1 1)
					(thickness 0.15)
				)
				(justify mirror)
			)
		)
		(property "Voltage" "50V"
			(at 250.313664 65.69632 0)
			(layer "B.Fab")
			(hide yes)
			(effects
				(font
					(size 1 1)
					(thickness 0.15)
				)
				(justify mirror)
			)
		)
		(sheetname "/Ethernet/")
		(sheetfile "ethernet.kicad_sch")
		(attr smd)
		(fp_rect
			(start -0.9659 0.481258)
			(end 0.9649 -0.458742)
			(stroke
				(width 0.05)
				(type solid)
			)
			(fill no)
			(layer "B.CrtYd")
		)
		(fp_line
			(start 0.499 -0.248)
			(end -0.499 -0.248)
			(stroke
				(width 0.15)
				(type solid)
			)
			(layer "B.Fab")
		)
		(fp_line
			(start -0.499 -0.248)
			(end -0.499 0.25)
			(stroke
				(width 0.15)
				(type solid)
			)
			(layer "B.Fab")
		)
		(fp_line
			(start 0.499 0.25)
			(end 0.499 -0.248)
			(stroke
				(width 0.15)
				(type solid)
			)
			(layer "B.Fab")
		)
		(fp_line
			(start -0.499 0.25)
			(end 0.499 0.25)
			(stroke
				(width 0.15)
				(type solid)
			)
			(layer "B.Fab")
		)
		(pad "1" smd roundrect
			(at -0.484 0 90)
			(size 0.59 0.64)
			(layers "B.Cu" "B.Mask" "B.Paste")
			(roundrect_rratio 0.25)
			(net 199 "+1V2")
			(pintype "passive")
		)
		(pad "2" smd roundrect
			(at 0.484 0 90)
			(size 0.59 0.64)
			(layers "B.Cu" "B.Mask" "B.Paste")
			(roundrect_rratio 0.25)
			(net 1 "GND")
			(pintype "passive")
		)
	)
	(footprint "antmicro-footprints:C_0402_1005Metric"
		(layer "B.Cu")
		(at 89.086829 149.633157 90)
		(descr "Capacitor SMD 0402")
		(tags "capacitor SMD 0402")
		(property "Reference" "C158"
			(at 0 0.699 270)
			(layer "B.SilkS")
			(hide yes)
			(effects
				(font
					(size 0.7 0.7)
					(thickness 0.15)
				)
				(justify left bottom mirror)
			)
		)
		(property "Value" "C_4u7_0402"
			(at -1.022927 -2.155213 270)
			(layer "B.Fab")
			(effects
				(font
					(size 0.7 0.7)
					(thickness 0.15)
				)
				(justify left bottom mirror)
			)
		)
		(property "Datasheet" "https://www.murata.com/products/productdetail?partno=GRM155R61A475MEAA%23"
			(at 0 0 90)
			(layer "F.Fab")
			(hide yes)
			(effects
				(font
					(size 1.27 1.27)
					(thickness 0.15)
				)
			)
		)
		(property "Author" "Antmicro"
			(at 238.719986 60.546328 0)
			(layer "B.Fab")
			(hide yes)
			(effects
				(font
					(size 1 1)
					(thickness 0.15)
				)
				(justify mirror)
			)
		)
		(property "Dielectric" ""
			(at 238.719986 60.546328 0)
			(layer "B.Fab")
			(hide yes)
			(effects
				(font
					(size 1 1)
					(thickness 0.15)
				)
				(justify mirror)
			)
		)
		(property "License" "Apache-2.0"
			(at 238.719986 60.546328 0)
			(layer "B.Fab")
			(hide yes)
			(effects
				(font
					(size 1 1)
					(thickness 0.15)
				)
				(justify mirror)
			)
		)
		(property "MPN" "GRM155R61A475MEAAD"
			(at 238.719986 60.546328 0)
			(layer "B.Fab")
			(hide yes)
			(effects
				(font
					(size 1 1)
					(thickness 0.15)
				)
				(justify mirror)
			)
		)
		(property "Manufacturer" "Murata"
			(at 238.719986 60.546328 0)
			(layer "B.Fab")
			(hide yes)
			(effects
				(font
					(size 1 1)
					(thickness 0.15)
				)
				(justify mirror)
			)
		)
		(property "Val" "4u7"
			(at 238.719986 60.546328 0)
			(layer "B.Fab")
			(hide yes)
			(effects
				(font
					(size 1 1)
					(thickness 0.15)
				)
				(justify mirror)
			)
		)
		(property "Voltage" ""
			(at 238.719986 60.546328 0)
			(layer "B.Fab")
			(hide yes)
			(effects
				(font
					(size 1 1)
					(thickness 0.15)
				)
				(justify mirror)
			)
		)
		(sheetname "/Ethernet/")
		(sheetfile "ethernet.kicad_sch")
		(attr smd)
		(fp_rect
			(start -0.9659 0.481258)
			(end 0.9649 -0.458742)
			(stroke
				(width 0.05)
				(type solid)
			)
			(fill no)
			(layer "B.CrtYd")
		)
		(fp_line
			(start 0.499 -0.248)
			(end -0.499 -0.248)
			(stroke
				(width 0.15)
				(type solid)
			)
			(layer "B.Fab")
		)
		(fp_line
			(start -0.499 -0.248)
			(end -0.499 0.25)
			(stroke
				(width 0.15)
				(type solid)
			)
			(layer "B.Fab")
		)
		(fp_line
			(start 0.499 0.25)
			(end 0.499 -0.248)
			(stroke
				(width 0.15)
				(type solid)
			)
			(layer "B.Fab")
		)
		(fp_line
			(start -0.499 0.25)
			(end 0.499 0.25)
			(stroke
				(width 0.15)
				(type solid)
			)
			(layer "B.Fab")
		)
		(pad "1" smd roundrect
			(at -0.484 0 90)
			(size 0.59 0.64)
			(layers "B.Cu" "B.Mask" "B.Paste")
			(roundrect_rratio 0.25)
			(net 134 "/Ethernet/AVDDH")
			(pintype "passive")
		)
		(pad "2" smd roundrect
			(at 0.484 0 90)
			(size 0.59 0.64)
			(layers "B.Cu" "B.Mask" "B.Paste")
			(roundrect_rratio 0.25)
			(net 1 "GND")
			(pintype "passive")
		)
	)
	(footprint "antmicro-footprints:C_0402_1005Metric"
		(layer "B.Cu")
		(at 90.108672 158.004992 90)
		(descr "Capacitor SMD 0402")
		(tags "capacitor SMD 0402")
		(property "Reference" "C153"
			(at 0 0.699 270)
			(layer "B.SilkS")
			(hide yes)
			(effects
				(font
					(size 0.7 0.7)
					(thickness 0.15)
				)
				(justify left bottom mirror)
			)
		)
		(property "Value" "C_10n_0402"
			(at -1.022927 -2.155213 270)
			(layer "B.Fab")
			(effects
				(font
					(size 0.7 0.7)
					(thickness 0.15)
				)
				(justify left bottom mirror)
			)
		)
		(property "Datasheet" "https://www.murata.com/products/productdetail?partno=GRM155R71H103KA88%23"
			(at 0 0 90)
			(layer "F.Fab")
			(hide yes)
			(effects
				(font
					(size 1.27 1.27)
					(thickness 0.15)
				)
			)
		)
		(property "Author" "Antmicro"
			(at 248.113664 67.89632 0)
			(layer "B.Fab")
			(hide yes)
			(effects
				(font
					(size 1 1)
					(thickness 0.15)
				)
				(justify mirror)
			)
		)
		(property "Dielectric" "X7R"
			(at 248.113664 67.89632 0)
			(layer "B.Fab")
			(hide yes)
			(effects
				(font
					(size 1 1)
					(thickness 0.15)
				)
				(justify mirror)
			)
		)
		(property "License" "Apache-2.0"
			(at 248.113664 67.89632 0)
			(layer "B.Fab")
			(hide yes)
			(effects
				(font
					(size 1 1)
					(thickness 0.15)
				)
				(justify mirror)
			)
		)
		(property "MPN" "GRM155R71H103KA88D"
			(at 248.113664 67.89632 0)
			(layer "B.Fab")
			(hide yes)
			(effects
				(font
					(size 1 1)
					(thickness 0.15)
				)
				(justify mirror)
			)
		)
		(property "Manufacturer" "Murata"
			(at 248.113664 67.89632 0)
			(layer "B.Fab")
			(hide yes)
			(effects
				(font
					(size 1 1)
					(thickness 0.15)
				)
				(justify mirror)
			)
		)
		(property "Val" "10n"
			(at 248.113664 67.89632 0)
			(layer "B.Fab")
			(hide yes)
			(effects
				(font
					(size 1 1)
					(thickness 0.15)
				)
				(justify mirror)
			)
		)
		(property "Voltage" "50V"
			(at 248.113664 67.89632 0)
			(layer "B.Fab")
			(hide yes)
			(effects
				(font
					(size 1 1)
					(thickness 0.15)
				)
				(justify mirror)
			)
		)
		(sheetname "/Ethernet/")
		(sheetfile "ethernet.kicad_sch")
		(attr smd)
		(fp_rect
			(start -0.9659 0.481258)
			(end 0.9649 -0.458742)
			(stroke
				(width 0.05)
				(type solid)
			)
			(fill no)
			(layer "B.CrtYd")
		)
		(fp_line
			(start 0.499 -0.248)
			(end -0.499 -0.248)
			(stroke
				(width 0.15)
				(type solid)
			)
			(layer "B.Fab")
		)
		(fp_line
			(start -0.499 -0.248)
			(end -0.499 0.25)
			(stroke
				(width 0.15)
				(type solid)
			)
			(layer "B.Fab")
		)
		(fp_line
			(start 0.499 0.25)
			(end 0.499 -0.248)
			(stroke
				(width 0.15)
				(type solid)
			)
			(layer "B.Fab")
		)
		(fp_line
			(start -0.499 0.25)
			(end 0.499 0.25)
			(stroke
				(width 0.15)
				(type solid)
			)
			(layer "B.Fab")
		)
		(pad "1" smd roundrect
			(at -0.484 0 90)
			(size 0.59 0.64)
			(layers "B.Cu" "B.Mask" "B.Paste")
			(roundrect_rratio 0.25)
			(net 199 "+1V2")
			(pintype "passive")
		)
		(pad "2" smd roundrect
			(at 0.484 0 90)
			(size 0.59 0.64)
			(layers "B.Cu" "B.Mask" "B.Paste")
			(roundrect_rratio 0.25)
			(net 1 "GND")
			(pintype "passive")
		)
	)
	(footprint "antmicro-footprints:FB_0603_1608Metric"
		(layer "B.Cu")
		(at 98.200501 149.558851 180)
		(property "Reference" "FB5"
			(at 0 0.8 0)
			(layer "B.SilkS")
			(hide yes)
			(effects
				(font
					(size 0.7 0.7)
					(thickness 0.15)
				)
				(justify left bottom mirror)
			)
		)
		(property "Value" "FB_120Z_2A_Murata-BLM18PG_0603"
			(at 0 -1.5 0)
			(layer "B.Fab")
			(effects
				(font
					(size 0.7 0.7)
					(thickness 0.15)
				)
				(justify left bottom mirror)
			)
		)
		(property "Datasheet" "https://www.murata.com/en-us/products/productdata/8796738650142/ENFA0003.pdf"
			(at 0 0 180)
			(layer "F.Fab")
			(hide yes)
			(effects
				(font
					(size 1.27 1.27)
					(thickness 0.15)
				)
			)
		)
		(property "Author" "Antmicro"
			(at 196.401002 299.117702 0)
			(layer "B.Fab")
			(hide yes)
			(effects
				(font
					(size 1 1)
					(thickness 0.15)
				)
				(justify mirror)
			)
		)
		(property "License" "Apache-2.0"
			(at 196.401002 299.117702 0)
			(layer "B.Fab")
			(hide yes)
			(effects
				(font
					(size 1 1)
					(thickness 0.15)
				)
				(justify mirror)
			)
		)
		(property "MPN" "BLM18PG121SN1D"
			(at 196.401002 299.117702 0)
			(layer "B.Fab")
			(hide yes)
			(effects
				(font
					(size 1 1)
					(thickness 0.15)
				)
				(justify mirror)
			)
		)
		(property "Manufacturer" "Murata"
			(at 196.401002 299.117702 0)
			(layer "B.Fab")
			(hide yes)
			(effects
				(font
					(size 1 1)
					(thickness 0.15)
				)
				(justify mirror)
			)
		)
		(property "Val" "120Z/2A"
			(at 196.401002 299.117702 0)
			(layer "B.Fab")
			(hide yes)
			(effects
				(font
					(size 1 1)
					(thickness 0.15)
				)
				(justify mirror)
			)
		)
		(sheetname "/Ethernet/")
		(sheetfile "ethernet.kicad_sch")
		(attr smd)
		(fp_line
			(start -0.196 0.408)
			(end 0.193 0.408)
			(stroke
				(width 0.15)
				(type solid)
			)
			(layer "B.SilkS")
		)
		(fp_line
			(start -0.196 -0.406)
			(end 0.193 -0.406)
			(stroke
				(width 0.15)
				(type solid)
			)
			(layer "B.SilkS")
		)
		(fp_rect
			(start -1.3 0.6)
			(end 1.3 -0.6)
			(stroke
				(width 0.05)
				(type solid)
			)
			(fill no)
			(layer "B.CrtYd")
		)
		(fp_line
			(start 0.8 0.408)
			(end 0.8 -0.406)
			(stroke
				(width 0.15)
				(type solid)
			)
			(layer "B.Fab")
		)
		(fp_line
			(start 0.8 0.408)
			(end -0.803 0.408)
			(stroke
				(width 0.15)
				(type solid)
			)
			(layer "B.Fab")
		)
		(fp_line
			(start 0.8 -0.406)
			(end -0.803 -0.406)
			(stroke
				(width 0.15)
				(type solid)
			)
			(layer "B.Fab")
		)
		(fp_line
			(start -0.803 -0.406)
			(end -0.803 0.408)
			(stroke
				(width 0.15)
				(type solid)
			)
			(layer "B.Fab")
		)
		(pad "1" smd roundrect
			(at -0.891 0 180)
			(size 0.762 1.09)
			(layers "B.Cu" "B.Mask" "B.Paste")
			(roundrect_rratio 0.15)
			(net 200 "+3V3")
			(pintype "passive")
		)
		(pad "2" smd roundrect
			(at 0.888 0 180)
			(size 0.762 1.09)
			(layers "B.Cu" "B.Mask" "B.Paste")
			(roundrect_rratio 0.15)
			(net 134 "/Ethernet/AVDDH")
			(pintype "passive")
		)
	)
	(footprint "antmicro-footprints:FB_0603_1608Metric"
		(layer "B.Cu")
		(at 93.086829 152.558157)
		(property "Reference" "FB4"
			(at 0 0.8 180)
			(layer "B.SilkS")
			(hide yes)
			(effects
				(font
					(size 0.7 0.7)
					(thickness 0.15)
				)
				(justify left bottom mirror)
			)
		)
		(property "Value" "FB_120Z_2A_Murata-BLM18PG_0603"
			(at 0 -1.5 180)
			(layer "B.Fab")
			(effects
				(font
					(size 0.7 0.7)
					(thickness 0.15)
				)
				(justify left bottom mirror)
			)
		)
		(property "Datasheet" "https://www.murata.com/en-us/products/productdata/8796738650142/ENFA0003.pdf"
			(at 0 0 0)
			(layer "F.Fab")
			(hide yes)
			(effects
				(font
					(size 1.27 1.27)
					(thickness 0.15)
				)
			)
		)
		(property "Author" "Antmicro"
			(at 0 0 0)
			(layer "B.Fab")
			(hide yes)
			(effects
				(font
					(size 1 1)
					(thickness 0.15)
				)
				(justify mirror)
			)
		)
		(property "License" "Apache-2.0"
			(at 0 0 0)
			(layer "B.Fab")
			(hide yes)
			(effects
				(font
					(size 1 1)
					(thickness 0.15)
				)
				(justify mirror)
			)
		)
		(property "MPN" "BLM18PG121SN1D"
			(at 0 0 0)
			(layer "B.Fab")
			(hide yes)
			(effects
				(font
					(size 1 1)
					(thickness 0.15)
				)
				(justify mirror)
			)
		)
		(property "Manufacturer" "Murata"
			(at 0 0 0)
			(layer "B.Fab")
			(hide yes)
			(effects
				(font
					(size 1 1)
					(thickness 0.15)
				)
				(justify mirror)
			)
		)
		(property "Val" "120Z/2A"
			(at 0 0 0)
			(layer "B.Fab")
			(hide yes)
			(effects
				(font
					(size 1 1)
					(thickness 0.15)
				)
				(justify mirror)
			)
		)
		(sheetname "/Ethernet/")
		(sheetfile "ethernet.kicad_sch")
		(attr smd)
		(fp_line
			(start -0.196 -0.406)
			(end 0.193 -0.406)
			(stroke
				(width 0.15)
				(type solid)
			)
			(layer "B.SilkS")
		)
		(fp_line
			(start -0.196 0.408)
			(end 0.193 0.408)
			(stroke
				(width 0.15)
				(type solid)
			)
			(layer "B.SilkS")
		)
		(fp_rect
			(start -1.3 0.6)
			(end 1.3 -0.6)
			(stroke
				(width 0.05)
				(type solid)
			)
			(fill no)
			(layer "B.CrtYd")
		)
		(fp_line
			(start -0.803 -0.406)
			(end -0.803 0.408)
			(stroke
				(width 0.15)
				(type solid)
			)
			(layer "B.Fab")
		)
		(fp_line
			(start 0.8 -0.406)
			(end -0.803 -0.406)
			(stroke
				(width 0.15)
				(type solid)
			)
			(layer "B.Fab")
		)
		(fp_line
			(start 0.8 0.408)
			(end -0.803 0.408)
			(stroke
				(width 0.15)
				(type solid)
			)
			(layer "B.Fab")
		)
		(fp_line
			(start 0.8 0.408)
			(end 0.8 -0.406)
			(stroke
				(width 0.15)
				(type solid)
			)
			(layer "B.Fab")
		)
		(pad "1" smd roundrect
			(at -0.891 0)
			(size 0.762 1.09)
			(layers "B.Cu" "B.Mask" "B.Paste")
			(roundrect_rratio 0.15)
			(net 199 "+1V2")
			(pintype "passive")
		)
		(pad "2" smd roundrect
			(at 0.888 0)
			(size 0.762 1.09)
			(layers "B.Cu" "B.Mask" "B.Paste")
			(roundrect_rratio 0.15)
			(net 132 "/Ethernet/AVDDL")
			(pintype "passive")
		)
	)
)
